# T6G (Grand Teton) — schematic netlist excerpt (pin names and nets, part order shuffled) for the footprints in the layout excerpt that follows; sources: Cadence DE-HDL packaged netlist, KiCad conversion of 04192023_DAF0TMB3IC0_F0TG_MB_C_brd_V02_OCP.brd

C1082  Q_CAP  100PF 50V 5% EMPTY  pkg 0402  page 258 : A = PVDD_33_S5_ADC_MAM ; B = GND
C538  Q_CAP  0.1UF 10V 10% X7S  pkg C0201  page 279 : A = P0V9_CPU0_RT0_2A_2D ; B = GND
C321  Q_CAP  10UF 6.3V 20% X6S  pkg C0402  page 334 : A = P0V9_CPU1_RT1_2A ; B = GND

(kicad_pcb
	(version 20260206)
	(generator "pcbnew")
	(generator_version "10.0")
	(general
		(thickness 1.6)
		(legacy_teardrops no)
	)
	(paper "A4")
	(title_block
		(title "04192023_DAF0TMB3IC0_F0TG_MB_C_brd_V02_OCP.brd")
		(comment 1 "Grand Teton / footprints 7305-7307 of 8354")
	)
	(layers
		(0 "F.Cu" signal "TOP")
		(4 "In1.Cu" signal "GND")
		(6 "In2.Cu" signal "IN1")
		(8 "In3.Cu" signal "GND1")
		(10 "In4.Cu" signal "IN2")
		(12 "In5.Cu" signal "GND2")
		(14 "In6.Cu" signal "IN3")
		(16 "In7.Cu" signal "GND3")
		(18 "In8.Cu" signal "VCC")
		(20 "In9.Cu" signal "VCC1")
		(22 "In10.Cu" signal "GND4")
		(24 "In11.Cu" signal "IN4")
		(26 "In12.Cu" signal "GND5")
		(28 "In13.Cu" signal "IN5")
		(30 "In14.Cu" signal "GND6")
		(32 "In15.Cu" signal "IN6")
		(34 "In16.Cu" signal "GND7")
		(2 "B.Cu" signal "BOTTOM")
		(9 "F.Adhes" user "F.Adhesive")
		(11 "B.Adhes" user "B.Adhesive")
		(13 "F.Paste" user "Package Geometry/Pastemask Top")
		(15 "B.Paste" user "Package Geometry/Pastemask Bottom")
		(5 "F.SilkS" user "Ref Des/Silkscreen Top")
		(7 "B.SilkS" user "Ref Des/Silkscreen Bottom")
		(1 "F.Mask" user "Board Geometry/Soldermask Top")
		(3 "B.Mask" user "Board Geometry/Soldermask Bottom")
		(17 "Dwgs.User" user "User.Drawings")
		(19 "Cmts.User" user "User.Comments")
		(21 "Eco1.User" user "User.Eco1")
		(23 "Eco2.User" user "User.Eco2")
		(25 "Edge.Cuts" user "Board Geometry/Outline")
		(27 "Margin" user)
		(31 "F.CrtYd" user "Package Geometry/Place Bound Top")
		(29 "B.CrtYd" user "Package Geometry/Place Bound Bottom")
		(35 "F.Fab" user "Ref Des/Assembly Top")
		(33 "B.Fab" user "Ref Des/Assembly Bottom")
	)
	(footprint ""
		(layer "B.Cu")
		(at 243.713 -322.834)
		(property "Reference" "C1082"
			(at 0 0 0)
			(layer "B.SilkS")
			(hide yes)
			(effects
				(font
					(size 1.27 1.27)
				)
				(justify mirror)
			)
		)
		(property "Value" ""
			(at 0 0 0)
			(layer "B.Fab")
			(effects
				(font
					(size 1.27 1.27)
				)
				(justify mirror)
			)
		)
		(duplicate_pad_numbers_are_jumpers no)
		(fp_line
			(start -0.7874 -0.4064)
			(end -0.7874 0.4064)
			(stroke
				(width 0.1524)
				(type default)
			)
			(layer "B.SilkS")
		)
		(fp_line
			(start -0.7874 0.4064)
			(end 0.7874 0.4064)
			(stroke
				(width 0.1524)
				(type default)
			)
			(layer "B.SilkS")
		)
		(fp_line
			(start 0.7874 -0.4064)
			(end -0.7874 -0.4064)
			(stroke
				(width 0.1524)
				(type default)
			)
			(layer "B.SilkS")
		)
		(fp_line
			(start 0.7874 0.4064)
			(end 0.7874 -0.4064)
			(stroke
				(width 0.1524)
				(type default)
			)
			(layer "B.SilkS")
		)
		(fp_line
			(start -0.67945 -0.3048)
			(end -0.67945 0.3048)
			(stroke
				(width 0.1)
				(type default)
			)
			(layer "B.Fab")
		)
		(fp_line
			(start -0.67945 0.3048)
			(end -0.120396 0.3048)
			(stroke
				(width 0.1)
				(type default)
			)
			(layer "B.Fab")
		)
		(fp_line
			(start -0.12065 -0.3048)
			(end -0.67945 -0.3048)
			(stroke
				(width 0.1)
				(type default)
			)
			(layer "B.Fab")
		)
		(fp_line
			(start -0.12065 -0.2794)
			(end -0.12065 -0.3048)
			(stroke
				(width 0.1)
				(type default)
			)
			(layer "B.Fab")
		)
		(fp_line
			(start -0.120396 0.2794)
			(end 0.12065 0.2794)
			(stroke
				(width 0.1)
				(type default)
			)
			(layer "B.Fab")
		)
		(fp_line
			(start -0.120396 0.3048)
			(end -0.120396 0.2794)
			(stroke
				(width 0.1)
				(type default)
			)
			(layer "B.Fab")
		)
		(fp_line
			(start 0.12065 -0.305054)
			(end 0.12065 -0.2794)
			(stroke
				(width 0.1)
				(type default)
			)
			(layer "B.Fab")
		)
		(fp_line
			(start 0.12065 -0.2794)
			(end -0.12065 -0.2794)
			(stroke
				(width 0.1)
				(type default)
			)
			(layer "B.Fab")
		)
		(fp_line
			(start 0.12065 0.2794)
			(end 0.12065 0.3048)
			(stroke
				(width 0.1)
				(type default)
			)
			(layer "B.Fab")
		)
		(fp_line
			(start 0.12065 0.3048)
			(end 0.67945 0.3048)
			(stroke
				(width 0.1)
				(type default)
			)
			(layer "B.Fab")
		)
		(fp_line
			(start 0.67945 -0.305054)
			(end 0.12065 -0.305054)
			(stroke
				(width 0.1)
				(type default)
			)
			(layer "B.Fab")
		)
		(fp_line
			(start 0.67945 0.3048)
			(end 0.67945 -0.305054)
			(stroke
				(width 0.1)
				(type default)
			)
			(layer "B.Fab")
		)
		(pad "1" smd circle
			(at 0.40005 0 180)
			(size 0 0)
			(layers "B.Cu" "B.Mask" "B.Paste")
			(net "PVDD_33_S5_ADC_MAM")
		)
		(pad "2" smd circle
			(at -0.40005 0 180)
			(size 0 0)
			(layers "B.Cu" "B.Mask" "B.Paste")
			(net "GND")
		)
	)
	(footprint ""
		(layer "B.Cu")
		(at 308.318154 -396.393162 -90)
		(property "Reference" "C538"
			(at 0 0 90)
			(layer "B.SilkS")
			(hide yes)
			(effects
				(font
					(size 1.27 1.27)
				)
				(justify mirror)
			)
		)
		(property "Value" ""
			(at 0 0 90)
			(layer "B.Fab")
			(effects
				(font
					(size 1.27 1.27)
				)
				(justify mirror)
			)
		)
		(duplicate_pad_numbers_are_jumpers no)
		(fp_line
			(start -0.299974 0.150114)
			(end 0.299974 0.150114)
			(stroke
				(width 0.1)
				(type default)
			)
			(layer "B.Fab")
		)
		(fp_line
			(start 0.299974 0.150114)
			(end 0.299974 -0.150114)
			(stroke
				(width 0.1)
				(type default)
			)
			(layer "B.Fab")
		)
		(fp_line
			(start -0.299974 -0.150114)
			(end -0.299974 0.150114)
			(stroke
				(width 0.1)
				(type default)
			)
			(layer "B.Fab")
		)
		(fp_line
			(start 0.299974 -0.150114)
			(end -0.299974 -0.150114)
			(stroke
				(width 0.1)
				(type default)
			)
			(layer "B.Fab")
		)
		(pad "1" smd rect
			(at 0.2667 0 90)
			(size 0.3048 0.381)
			(layers "B.Cu" "B.Mask" "B.Paste")
			(net "P0V9_CPU0_RT0_2A_2D")
		)
		(pad "2" smd rect
			(at -0.2667 0 90)
			(size 0.3048 0.381)
			(layers "B.Cu" "B.Mask" "B.Paste")
			(net "GND")
		)
	)
	(footprint ""
		(layer "B.Cu")
		(at 83.51901 -390.560052 90)
		(property "Reference" "C321"
			(at 0 0 90)
			(layer "B.SilkS")
			(hide yes)
			(effects
				(font
					(size 1.27 1.27)
				)
				(justify mirror)
			)
		)
		(property "Value" ""
			(at 0 0 90)
			(layer "B.Fab")
			(effects
				(font
					(size 1.27 1.27)
				)
				(justify mirror)
			)
		)
		(duplicate_pad_numbers_are_jumpers no)
		(fp_line
			(start 0.7874 -0.4064)
			(end -0.7874 -0.4064)
			(stroke
				(width 0.1524)
				(type default)
			)
			(layer "B.SilkS")
		)
		(fp_line
			(start -0.7874 -0.4064)
			(end -0.7874 0.4064)
			(stroke
				(width 0.1524)
				(type default)
			)
			(layer "B.SilkS")
		)
		(fp_line
			(start 0.7874 0.4064)
			(end 0.7874 -0.4064)
			(stroke
				(width 0.1524)
				(type default)
			)
			(layer "B.SilkS")
		)
		(fp_line
			(start -0.7874 0.4064)
			(end 0.7874 0.4064)
			(stroke
				(width 0.1524)
				(type default)
			)
			(layer "B.SilkS")
		)
		(fp_line
			(start 0.67945 -0.305054)
			(end 0.12065 -0.305054)
			(stroke
				(width 0.1)
				(type default)
			)
			(layer "B.Fab")
		)
		(fp_line
			(start 0.12065 -0.305054)
			(end 0.12065 -0.2794)
			(stroke
				(width 0.1)
				(type default)
			)
			(layer "B.Fab")
		)
		(fp_line
			(start -0.12065 -0.3048)
			(end -0.67945 -0.3048)
			(stroke
				(width 0.1)
				(type default)
			)
			(layer "B.Fab")
		)
		(fp_line
			(start -0.67945 -0.3048)
			(end -0.67945 0.3048)
			(stroke
				(width 0.1)
				(type default)
			)
			(layer "B.Fab")
		)
		(fp_line
			(start 0.12065 -0.2794)
			(end -0.12065 -0.2794)
			(stroke
				(width 0.1)
				(type default)
			)
			(layer "B.Fab")
		)
		(fp_line
			(start -0.12065 -0.2794)
			(end -0.12065 -0.3048)
			(stroke
				(width 0.1)
				(type default)
			)
			(layer "B.Fab")
		)
		(fp_line
			(start 0.12065 0.2794)
			(end 0.12065 0.3048)
			(stroke
				(width 0.1)
				(type default)
			)
			(layer "B.Fab")
		)
		(fp_line
			(start -0.120396 0.2794)
			(end 0.12065 0.2794)
			(stroke
				(width 0.1)
				(type default)
			)
			(layer "B.Fab")
		)
		(fp_line
			(start 0.67945 0.3048)
			(end 0.67945 -0.305054)
			(stroke
				(width 0.1)
				(type default)
			)
			(layer "B.Fab")
		)
		(fp_line
			(start 0.12065 0.3048)
			(end 0.67945 0.3048)
			(stroke
				(width 0.1)
				(type default)
			)
			(layer "B.Fab")
		)
		(fp_line
			(start -0.120396 0.3048)
			(end -0.120396 0.2794)
			(stroke
				(width 0.1)
				(type default)
			)
			(layer "B.Fab")
		)
		(fp_line
			(start -0.67945 0.3048)
			(end -0.120396 0.3048)
			(stroke
				(width 0.1)
				(type default)
			)
			(layer "B.Fab")
		)
		(pad "1" smd circle
			(at 0.40005 0 270)
			(size 0 0)
			(layers "B.Cu" "B.Mask" "B.Paste")
			(net "P0V9_CPU1_RT1_2A")
		)
		(pad "2" smd circle
			(at -0.40005 0 270)
			(size 0 0)
			(layers "B.Cu" "B.Mask" "B.Paste")
			(net "GND")
		)
	)
)
